(kicad_pcb
	(version 20260206)
	(generator "pcbnew")
	(generator_version "10.0")
	(general
		(thickness 1.6)
		(legacy_teardrops no)
	)
	(paper "A4")
	(title_block
		(title "01162023_DA0F0TEBIF0_F0T_Expander_BD_F_brd_V02_OCP.brd")
		(comment 1 "Grand Teton / footprints 4938-4943 of 9728")
	)
	(layers
		(0 "F.Cu" signal "TOP")
		(4 "In1.Cu" signal "GND")
		(6 "In2.Cu" signal "VCC")
		(8 "In3.Cu" signal "VCC1")
		(10 "In4.Cu" signal "GND1")
		(12 "In5.Cu" signal "IN1")
		(14 "In6.Cu" signal "GND2")
		(16 "In7.Cu" signal "IN2")
		(18 "In8.Cu" signal "GND3")
		(20 "In9.Cu" signal "IN3")
		(22 "In10.Cu" signal "GND4")
		(24 "In11.Cu" signal "IN4")
		(26 "In12.Cu" signal "GND5")
		(28 "In13.Cu" signal "IN5")
		(30 "In14.Cu" signal "GND6")
		(32 "In15.Cu" signal "IN6")
		(34 "In16.Cu" signal "GND7")
		(2 "B.Cu" signal "BOTTOM")
		(9 "F.Adhes" user "F.Adhesive")
		(11 "B.Adhes" user "B.Adhesive")
		(13 "F.Paste" user "Package Geometry/Pastemask Top")
		(15 "B.Paste" user "Package Geometry/Pastemask Bottom")
		(5 "F.SilkS" user "Ref Des/Silkscreen Top")
		(7 "B.SilkS" user "Ref Des/Silkscreen Bottom")
		(1 "F.Mask" user "Board Geometry/Soldermask Top")
		(3 "B.Mask" user "Board Geometry/Soldermask Bottom")
		(17 "Dwgs.User" user "User.Drawings")
		(19 "Cmts.User" user "User.Comments")
		(21 "Eco1.User" user "User.Eco1")
		(23 "Eco2.User" user "User.Eco2")
		(25 "Edge.Cuts" user "Board Geometry/Outline")
		(27 "Margin" user)
		(31 "F.CrtYd" user "Package Geometry/Place Bound Top")
		(29 "B.CrtYd" user "Package Geometry/Place Bound Bottom")
		(35 "F.Fab" user "Ref Des/Assembly Top")
		(33 "B.Fab" user "Ref Des/Assembly Bottom")
	)
	(footprint ""
		(layer "F.Cu")
		(at 351.15627 -32.848042 -90)
		(property "Reference" "R6102"
			(at 0 0 270)
			(layer "F.SilkS")
			(hide yes)
			(effects
				(font
					(size 1.27 1.27)
				)
			)
		)
		(property "Value" ""
			(at 0 0 270)
			(layer "F.Fab")
			(effects
				(font
					(size 1.27 1.27)
				)
			)
		)
		(duplicate_pad_numbers_are_jumpers no)
		(fp_line
			(start -0.7874 0.4064)
			(end -0.7874 -0.4064)
			(stroke
				(width 0.1524)
				(type default)
			)
			(layer "F.SilkS")
		)
		(fp_line
			(start 0.7874 0.4064)
			(end -0.7874 0.4064)
			(stroke
				(width 0.1524)
				(type default)
			)
			(layer "F.SilkS")
		)
		(fp_line
			(start -0.7874 -0.4064)
			(end 0.7874 -0.4064)
			(stroke
				(width 0.1524)
				(type default)
			)
			(layer "F.SilkS")
		)
		(fp_line
			(start 0.7874 -0.4064)
			(end 0.7874 0.4064)
			(stroke
				(width 0.1524)
				(type default)
			)
			(layer "F.SilkS")
		)
		(fp_line
			(start -0.67945 0.3048)
			(end -0.67945 -0.305054)
			(stroke
				(width 0.1)
				(type default)
			)
			(layer "F.Fab")
		)
		(fp_line
			(start -0.12065 0.3048)
			(end -0.67945 0.3048)
			(stroke
				(width 0.1)
				(type default)
			)
			(layer "F.Fab")
		)
		(fp_line
			(start 0.120396 0.3048)
			(end 0.120396 0.2794)
			(stroke
				(width 0.1)
				(type default)
			)
			(layer "F.Fab")
		)
		(fp_line
			(start 0.67945 0.3048)
			(end 0.120396 0.3048)
			(stroke
				(width 0.1)
				(type default)
			)
			(layer "F.Fab")
		)
		(fp_line
			(start -0.12065 0.2794)
			(end -0.12065 0.3048)
			(stroke
				(width 0.1)
				(type default)
			)
			(layer "F.Fab")
		)
		(fp_line
			(start 0.120396 0.2794)
			(end -0.12065 0.2794)
			(stroke
				(width 0.1)
				(type default)
			)
			(layer "F.Fab")
		)
		(fp_line
			(start -0.12065 -0.2794)
			(end 0.12065 -0.2794)
			(stroke
				(width 0.1)
				(type default)
			)
			(layer "F.Fab")
		)
		(fp_line
			(start 0.12065 -0.2794)
			(end 0.12065 -0.3048)
			(stroke
				(width 0.1)
				(type default)
			)
			(layer "F.Fab")
		)
		(fp_line
			(start 0.12065 -0.3048)
			(end 0.67945 -0.3048)
			(stroke
				(width 0.1)
				(type default)
			)
			(layer "F.Fab")
		)
		(fp_line
			(start 0.67945 -0.3048)
			(end 0.67945 0.3048)
			(stroke
				(width 0.1)
				(type default)
			)
			(layer "F.Fab")
		)
		(fp_line
			(start -0.67945 -0.305054)
			(end -0.12065 -0.305054)
			(stroke
				(width 0.1)
				(type default)
			)
			(layer "F.Fab")
		)
		(fp_line
			(start -0.12065 -0.305054)
			(end -0.12065 -0.2794)
			(stroke
				(width 0.1)
				(type default)
			)
			(layer "F.Fab")
		)
		(pad "1" smd circle
			(at -0.40005 0 270)
			(size 0 0)
			(layers "F.Cu" "F.Mask" "F.Paste")
			(net "SSD12_AUX_P3V3_EN_R")
		)
		(pad "2" smd circle
			(at 0.40005 0 270)
			(size 0 0)
			(layers "F.Cu" "F.Mask" "F.Paste")
			(net "P3V3_SSD12_CO_EN")
		)
	)
	(footprint ""
		(layer "F.Cu")
		(at 358.168194 -391.047478 180)
		(property "Reference" "R6696"
			(at 0 0 180)
			(layer "F.SilkS")
			(hide yes)
			(effects
				(font
					(size 1.27 1.27)
				)
			)
		)
		(property "Value" ""
			(at 0 0 180)
			(layer "F.Fab")
			(effects
				(font
					(size 1.27 1.27)
				)
			)
		)
		(duplicate_pad_numbers_are_jumpers no)
		(fp_line
			(start 0.7874 0.4064)
			(end -0.7874 0.4064)
			(stroke
				(width 0.1524)
				(type default)
			)
			(layer "F.SilkS")
		)
		(fp_line
			(start 0.7874 -0.4064)
			(end 0.7874 0.4064)
			(stroke
				(width 0.1524)
				(type default)
			)
			(layer "F.SilkS")
		)
		(fp_line
			(start -0.7874 0.4064)
			(end -0.7874 -0.4064)
			(stroke
				(width 0.1524)
				(type default)
			)
			(layer "F.SilkS")
		)
		(fp_line
			(start -0.7874 -0.4064)
			(end 0.7874 -0.4064)
			(stroke
				(width 0.1524)
				(type default)
			)
			(layer "F.SilkS")
		)
		(fp_line
			(start 0.67945 0.3048)
			(end 0.120396 0.3048)
			(stroke
				(width 0.1)
				(type default)
			)
			(layer "F.Fab")
		)
		(fp_line
			(start 0.67945 -0.3048)
			(end 0.67945 0.3048)
			(stroke
				(width 0.1)
				(type default)
			)
			(layer "F.Fab")
		)
		(fp_line
			(start 0.12065 -0.2794)
			(end 0.12065 -0.3048)
			(stroke
				(width 0.1)
				(type default)
			)
			(layer "F.Fab")
		)
		(fp_line
			(start 0.12065 -0.3048)
			(end 0.67945 -0.3048)
			(stroke
				(width 0.1)
				(type default)
			)
			(layer "F.Fab")
		)
		(fp_line
			(start 0.120396 0.3048)
			(end 0.120396 0.2794)
			(stroke
				(width 0.1)
				(type default)
			)
			(layer "F.Fab")
		)
		(fp_line
			(start 0.120396 0.2794)
			(end -0.12065 0.2794)
			(stroke
				(width 0.1)
				(type default)
			)
			(layer "F.Fab")
		)
		(fp_line
			(start -0.12065 0.3048)
			(end -0.67945 0.3048)
			(stroke
				(width 0.1)
				(type default)
			)
			(layer "F.Fab")
		)
		(fp_line
			(start -0.12065 0.2794)
			(end -0.12065 0.3048)
			(stroke
				(width 0.1)
				(type default)
			)
			(layer "F.Fab")
		)
		(fp_line
			(start -0.12065 -0.2794)
			(end 0.12065 -0.2794)
			(stroke
				(width 0.1)
				(type default)
			)
			(layer "F.Fab")
		)
		(fp_line
			(start -0.12065 -0.305054)
			(end -0.12065 -0.2794)
			(stroke
				(width 0.1)
				(type default)
			)
			(layer "F.Fab")
		)
		(fp_line
			(start -0.67945 0.3048)
			(end -0.67945 -0.305054)
			(stroke
				(width 0.1)
				(type default)
			)
			(layer "F.Fab")
		)
		(fp_line
			(start -0.67945 -0.305054)
			(end -0.12065 -0.305054)
			(stroke
				(width 0.1)
				(type default)
			)
			(layer "F.Fab")
		)
		(pad "1" smd circle
			(at -0.40005 0 180)
			(size 0 0)
			(layers "F.Cu" "F.Mask" "F.Paste")
			(net "MB_3V3IO_RSVD1_N")
		)
		(pad "2" smd circle
			(at 0.40005 0 180)
			(size 0 0)
			(layers "F.Cu" "F.Mask" "F.Paste")
			(net "P3V3_AUX")
		)
	)
	(footprint ""
		(layer "F.Cu")
		(at 248.698766 -254.192786 -90)
		(property "Reference" "C4357"
			(at 0 0 270)
			(layer "F.SilkS")
			(hide yes)
			(effects
				(font
					(size 1.27 1.27)
				)
			)
		)
		(property "Value" ""
			(at 0 0 270)
			(layer "F.Fab")
			(effects
				(font
					(size 1.27 1.27)
				)
			)
		)
		(duplicate_pad_numbers_are_jumpers no)
		(fp_line
			(start -1.524 0.762)
			(end -1.524 -0.762)
			(stroke
				(width 0.1524)
				(type default)
			)
			(layer "F.SilkS")
		)
		(fp_line
			(start 1.524 0.762)
			(end -1.524 0.762)
			(stroke
				(width 0.1524)
				(type default)
			)
			(layer "F.SilkS")
		)
		(fp_line
			(start -1.524 -0.762)
			(end 1.524 -0.762)
			(stroke
				(width 0.1524)
				(type default)
			)
			(layer "F.SilkS")
		)
		(fp_line
			(start 1.524 -0.762)
			(end 1.524 0.762)
			(stroke
				(width 0.1524)
				(type default)
			)
			(layer "F.SilkS")
		)
		(fp_line
			(start -1.1049 0.724916)
			(end 1.1049 0.724916)
			(stroke
				(width 0.1)
				(type default)
			)
			(layer "F.Fab")
		)
		(fp_line
			(start 1.1049 0.724916)
			(end 1.1049 -0.724916)
			(stroke
				(width 0.1)
				(type default)
			)
			(layer "F.Fab")
		)
		(fp_line
			(start -1.1049 -0.724916)
			(end -1.1049 0.724916)
			(stroke
				(width 0.1)
				(type default)
			)
			(layer "F.Fab")
		)
		(fp_line
			(start 1.1049 -0.724916)
			(end -1.1049 -0.724916)
			(stroke
				(width 0.1)
				(type default)
			)
			(layer "F.Fab")
		)
		(pad "1" smd rect
			(at -0.889 0 90)
			(size 1.016 1.27)
			(layers "F.Cu" "F.Mask" "F.Paste")
			(net "P1V25_SERDES_VDDPLL_PEX2_C11")
		)
		(pad "2" smd rect
			(at 0.889 0 90)
			(size 1.016 1.27)
			(layers "F.Cu" "F.Mask" "F.Paste")
			(net "GND")
		)
		(zone
			(layer "F.Cu")
			(hatch none 0.5)
			(connect_pads
				(clearance 0)
			)
			(min_thickness 0.25)
			(keepout
				(tracks not_allowed)
				(vias allowed)
				(pads allowed)
				(copperpour not_allowed)
				(footprints allowed)
			)
			(placement
				(enabled no)
				(sheetname "")
			)
			(fill
				(thermal_gap 0.5)
				(thermal_bridge_width 0.5)
				(island_removal_mode 0)
			)
			(polygon
				(pts
					(xy 249.423682 -254.522986) (xy 247.97385 -254.522986) (xy 247.97385 -253.862586) (xy 249.423682 -253.862586)
				)
			)
		)
	)
	(footprint ""
		(layer "F.Cu")
		(at 187.346844 -37.47516)
		(property "Reference" "R6075"
			(at 0 0 0)
			(layer "F.SilkS")
			(hide yes)
			(effects
				(font
					(size 1.27 1.27)
				)
			)
		)
		(property "Value" ""
			(at 0 0 0)
			(layer "F.Fab")
			(effects
				(font
					(size 1.27 1.27)
				)
			)
		)
		(duplicate_pad_numbers_are_jumpers no)
		(fp_line
			(start -0.7874 -0.4064)
			(end 0.7874 -0.4064)
			(stroke
				(width 0.1524)
				(type default)
			)
			(layer "F.SilkS")
		)
		(fp_line
			(start -0.7874 0.4064)
			(end -0.7874 -0.4064)
			(stroke
				(width 0.1524)
				(type default)
			)
			(layer "F.SilkS")
		)
		(fp_line
			(start 0.7874 -0.4064)
			(end 0.7874 0.4064)
			(stroke
				(width 0.1524)
				(type default)
			)
			(layer "F.SilkS")
		)
		(fp_line
			(start 0.7874 0.4064)
			(end -0.7874 0.4064)
			(stroke
				(width 0.1524)
				(type default)
			)
			(layer "F.SilkS")
		)
		(fp_line
			(start -0.67945 -0.305054)
			(end -0.12065 -0.305054)
			(stroke
				(width 0.1)
				(type default)
			)
			(layer "F.Fab")
		)
		(fp_line
			(start -0.67945 0.3048)
			(end -0.67945 -0.305054)
			(stroke
				(width 0.1)
				(type default)
			)
			(layer "F.Fab")
		)
		(fp_line
			(start -0.12065 -0.305054)
			(end -0.12065 -0.2794)
			(stroke
				(width 0.1)
				(type default)
			)
			(layer "F.Fab")
		)
		(fp_line
			(start -0.12065 -0.2794)
			(end 0.12065 -0.2794)
			(stroke
				(width 0.1)
				(type default)
			)
			(layer "F.Fab")
		)
		(fp_line
			(start -0.12065 0.2794)
			(end -0.12065 0.3048)
			(stroke
				(width 0.1)
				(type default)
			)
			(layer "F.Fab")
		)
		(fp_line
			(start -0.12065 0.3048)
			(end -0.67945 0.3048)
			(stroke
				(width 0.1)
				(type default)
			)
			(layer "F.Fab")
		)
		(fp_line
			(start 0.120396 0.2794)
			(end -0.12065 0.2794)
			(stroke
				(width 0.1)
				(type default)
			)
			(layer "F.Fab")
		)
		(fp_line
			(start 0.120396 0.3048)
			(end 0.120396 0.2794)
			(stroke
				(width 0.1)
				(type default)
			)
			(layer "F.Fab")
		)
		(fp_line
			(start 0.12065 -0.3048)
			(end 0.67945 -0.3048)
			(stroke
				(width 0.1)
				(type default)
			)
			(layer "F.Fab")
		)
		(fp_line
			(start 0.12065 -0.2794)
			(end 0.12065 -0.3048)
			(stroke
				(width 0.1)
				(type default)
			)
			(layer "F.Fab")
		)
		(fp_line
			(start 0.67945 -0.3048)
			(end 0.67945 0.3048)
			(stroke
				(width 0.1)
				(type default)
			)
			(layer "F.Fab")
		)
		(fp_line
			(start 0.67945 0.3048)
			(end 0.120396 0.3048)
			(stroke
				(width 0.1)
				(type default)
			)
			(layer "F.Fab")
		)
		(pad "1" smd circle
			(at -0.40005 0)
			(size 0 0)
			(layers "F.Cu" "F.Mask" "F.Paste")
			(net "P3V3_SSD7")
		)
		(pad "2" smd circle
			(at 0.40005 0)
			(size 0 0)
			(layers "F.Cu" "F.Mask" "F.Paste")
			(net "P3V3_SSD7_PG_G1")
		)
	)
	(footprint ""
		(layer "F.Cu")
		(at 142.343886 -49.95291 180)
		(property "Reference" "R555"
			(at 0 0 180)
			(layer "F.SilkS")
			(hide yes)
			(effects
				(font
					(size 1.27 1.27)
				)
			)
		)
		(property "Value" ""
			(at 0 0 180)
			(layer "F.Fab")
			(effects
				(font
					(size 1.27 1.27)
				)
			)
		)
		(duplicate_pad_numbers_are_jumpers no)
		(fp_line
			(start 0.7874 0.4064)
			(end -0.7874 0.4064)
			(stroke
				(width 0.1524)
				(type default)
			)
			(layer "F.SilkS")
		)
		(fp_line
			(start 0.7874 -0.4064)
			(end 0.7874 0.4064)
			(stroke
				(width 0.1524)
				(type default)
			)
			(layer "F.SilkS")
		)
		(fp_line
			(start -0.7874 0.4064)
			(end -0.7874 -0.4064)
			(stroke
				(width 0.1524)
				(type default)
			)
			(layer "F.SilkS")
		)
		(fp_line
			(start -0.7874 -0.4064)
			(end 0.7874 -0.4064)
			(stroke
				(width 0.1524)
				(type default)
			)
			(layer "F.SilkS")
		)
		(fp_line
			(start 0.67945 0.3048)
			(end 0.120396 0.3048)
			(stroke
				(width 0.1)
				(type default)
			)
			(layer "F.Fab")
		)
		(fp_line
			(start 0.67945 -0.3048)
			(end 0.67945 0.3048)
			(stroke
				(width 0.1)
				(type default)
			)
			(layer "F.Fab")
		)
		(fp_line
			(start 0.12065 -0.2794)
			(end 0.12065 -0.3048)
			(stroke
				(width 0.1)
				(type default)
			)
			(layer "F.Fab")
		)
		(fp_line
			(start 0.12065 -0.3048)
			(end 0.67945 -0.3048)
			(stroke
				(width 0.1)
				(type default)
			)
			(layer "F.Fab")
		)
		(fp_line
			(start 0.120396 0.3048)
			(end 0.120396 0.2794)
			(stroke
				(width 0.1)
				(type default)
			)
			(layer "F.Fab")
		)
		(fp_line
			(start 0.120396 0.2794)
			(end -0.12065 0.2794)
			(stroke
				(width 0.1)
				(type default)
			)
			(layer "F.Fab")
		)
		(fp_line
			(start -0.12065 0.3048)
			(end -0.67945 0.3048)
			(stroke
				(width 0.1)
				(type default)
			)
			(layer "F.Fab")
		)
		(fp_line
			(start -0.12065 0.2794)
			(end -0.12065 0.3048)
			(stroke
				(width 0.1)
				(type default)
			)
			(layer "F.Fab")
		)
		(fp_line
			(start -0.12065 -0.2794)
			(end 0.12065 -0.2794)
			(stroke
				(width 0.1)
				(type default)
			)
			(layer "F.Fab")
		)
		(fp_line
			(start -0.12065 -0.305054)
			(end -0.12065 -0.2794)
			(stroke
				(width 0.1)
				(type default)
			)
			(layer "F.Fab")
		)
		(fp_line
			(start -0.67945 0.3048)
			(end -0.67945 -0.305054)
			(stroke
				(width 0.1)
				(type default)
			)
			(layer "F.Fab")
		)
		(fp_line
			(start -0.67945 -0.305054)
			(end -0.12065 -0.305054)
			(stroke
				(width 0.1)
				(type default)
			)
			(layer "F.Fab")
		)
		(pad "1" smd circle
			(at -0.40005 0 180)
			(size 0 0)
			(layers "F.Cu" "F.Mask" "F.Paste")
			(net "SMB_BIC_I2C6_MUX_SSD_0_7_ADC_R_SCL")
		)
		(pad "2" smd circle
			(at 0.40005 0 180)
			(size 0 0)
			(layers "F.Cu" "F.Mask" "F.Paste")
			(net "SMB_SSD4_ADC_SCL")
		)
	)
	(footprint ""
		(layer "F.Cu")
		(at 10.530586 -142.035276 180)
		(property "Reference" "PC601"
			(at 0 0 180)
			(layer "F.SilkS")
			(hide yes)
			(effects
				(font
					(size 1.27 1.27)
				)
			)
		)
		(property "Value" ""
			(at 0 0 180)
			(layer "F.Fab")
			(effects
				(font
					(size 1.27 1.27)
				)
			)
		)
		(duplicate_pad_numbers_are_jumpers no)
		(fp_line
			(start 1.524 0.762)
			(end -1.524 0.762)
			(stroke
				(width 0.1524)
				(type default)
			)
			(layer "F.SilkS")
		)
		(fp_line
			(start 1.524 -0.762)
			(end 1.524 0.762)
			(stroke
				(width 0.1524)
				(type default)
			)
			(layer "F.SilkS")
		)
		(fp_line
			(start -1.524 0.762)
			(end -1.524 -0.762)
			(stroke
				(width 0.1524)
				(type default)
			)
			(layer "F.SilkS")
		)
		(fp_line
			(start -1.524 -0.762)
			(end 1.524 -0.762)
			(stroke
				(width 0.1524)
				(type default)
			)
			(layer "F.SilkS")
		)
		(fp_line
			(start 1.1049 0.724916)
			(end 1.1049 -0.724916)
			(stroke
				(width 0.1)
				(type default)
			)
			(layer "F.Fab")
		)
		(fp_line
			(start 1.1049 -0.724916)
			(end -1.1049 -0.724916)
			(stroke
				(width 0.1)
				(type default)
			)
			(layer "F.Fab")
		)
		(fp_line
			(start -1.1049 0.724916)
			(end 1.1049 0.724916)
			(stroke
				(width 0.1)
				(type default)
			)
			(layer "F.Fab")
		)
		(fp_line
			(start -1.1049 -0.724916)
			(end -1.1049 0.724916)
			(stroke
				(width 0.1)
				(type default)
			)
			(layer "F.Fab")
		)
		(pad "1" smd rect
			(at -0.889 0)
			(size 1.016 1.27)
			(layers "F.Cu" "F.Mask" "F.Paste")
			(net "P12V_NIC0_R")
		)
		(pad "2" smd rect
			(at 0.889 0)
			(size 1.016 1.27)
			(layers "F.Cu" "F.Mask" "F.Paste")
			(net "GND")
		)
	)
)
